(kicad_pcb
	(version 20260206)
	(generator "pcbnew")
	(generator_version "10.0")
	(general
		(thickness 1.6)
		(legacy_teardrops no)
	)
	(paper "A4")
	(title_block
		(title "dpb — 14545-sa.0730WZS0815.brd")
		(comment 1 "Honey Badger (Wiwynn) / footprints 357-363 of 1066")
	)
	(layers
		(0 "F.Cu" signal "TOP")
		(4 "In1.Cu" signal "L2GND")
		(6 "In2.Cu" signal "L3")
		(8 "In3.Cu" signal "L4VCC")
		(10 "In4.Cu" signal "L5VCC")
		(12 "In5.Cu" signal "L6")
		(14 "In6.Cu" signal "L7GND")
		(2 "B.Cu" signal "BOTTOM")
		(9 "F.Adhes" user "F.Adhesive")
		(11 "B.Adhes" user "B.Adhesive")
		(13 "F.Paste" user "Package Geometry/Pastemask Top")
		(15 "B.Paste" user "Package Geometry/Pastemask Bottom")
		(5 "F.SilkS" user "Ref Des/Silkscreen Top")
		(7 "B.SilkS" user "Ref Des/Silkscreen Bottom")
		(1 "F.Mask" user "Board Geometry/Soldermask Top")
		(3 "B.Mask" user "Board Geometry/Soldermask Bottom")
		(17 "Dwgs.User" user "User.Drawings")
		(19 "Cmts.User" user "User.Comments")
		(21 "Eco1.User" user "User.Eco1")
		(23 "Eco2.User" user "User.Eco2")
		(25 "Edge.Cuts" user "Board Geometry/Outline")
		(27 "Margin" user)
		(31 "F.CrtYd" user "Package Geometry/Place Bound Top")
		(29 "B.CrtYd" user "Package Geometry/Place Bound Bottom")
		(35 "F.Fab" user "Ref Des/Assembly Top")
		(33 "B.Fab" user "Ref Des/Assembly Bottom")
	)
	(footprint ""
		(layer "F.Cu")
		(at 33.273746 -270.1417 -90)
		(property "Reference" "C217"
			(at 0 0 270)
			(layer "F.SilkS")
			(hide yes)
			(effects
				(font
					(size 1.27 1.27)
				)
			)
		)
		(property "Value" "SCD01U50V2KX-1GP"
			(at 1.1811 -2.7051 270)
			(unlocked yes)
			(layer "F.Fab")
			(hide yes)
			(effects
				(font
					(size 1.016 1.016)
					(thickness 0.1524)
				)
			)
		)
		(property "Device Type" "C402H22"
			(at 1.1811 -4.2291 270)
			(unlocked yes)
			(layer "F.Fab")
			(hide yes)
			(effects
				(font
					(size 1.016 1.016)
					(thickness 0.1524)
				)
			)
		)
		(duplicate_pad_numbers_are_jumpers no)
		(fp_rect
			(start -0.4318 0.9525)
			(end 0.4318 -0.9525)
			(stroke
				(width 0)
				(type default)
			)
			(fill no)
			(layer "F.CrtYd")
		)
		(fp_rect
			(start -0.4318 0.9525)
			(end 0.4318 -0.9525)
			(stroke
				(width 0)
				(type default)
			)
			(fill no)
			(layer "F.Fab")
		)
		(pad "1" smd custom
			(at 0 -0.4445 270)
			(size 0.1524 0.1524)
			(layers "F.Cu" "F.Mask" "F.Paste")
			(net "SAS2X28_DRIVE_RX_P_B7")
			(options
				(clearance outline)
				(anchor circle)
			)
			(primitives
				(gr_poly
					(pts
						(arc
							(start 0.3048 -0.2032)
							(mid 0.275042 -0.275042)
							(end 0.2032 -0.3048)
						)
						(arc
							(start -0.2032 -0.3048)
							(mid -0.275042 -0.275042)
							(end -0.3048 -0.2032)
						)
						(arc
							(start -0.3048 0.2032)
							(mid -0.275042 0.275042)
							(end -0.2032 0.3048)
						)
						(arc
							(start 0.2032 0.3048)
							(mid 0.275042 0.275042)
							(end 0.3048 0.2032)
						)
					)
					(width 0)
					(fill yes)
				)
			)
		)
		(pad "2" smd custom
			(at 0 0.4445 270)
			(size 0.1524 0.1524)
			(layers "F.Cu" "F.Mask" "F.Paste")
			(net "SAS2X28_B_HDD7_RX_+")
			(options
				(clearance outline)
				(anchor circle)
			)
			(primitives
				(gr_poly
					(pts
						(arc
							(start 0.3048 -0.2032)
							(mid 0.275042 -0.275042)
							(end 0.2032 -0.3048)
						)
						(arc
							(start -0.2032 -0.3048)
							(mid -0.275042 -0.275042)
							(end -0.3048 -0.2032)
						)
						(arc
							(start -0.3048 0.2032)
							(mid -0.275042 0.275042)
							(end -0.2032 0.3048)
						)
						(arc
							(start 0.2032 0.3048)
							(mid 0.275042 0.275042)
							(end 0.3048 0.2032)
						)
					)
					(width 0)
					(fill yes)
				)
			)
		)
	)
	(footprint ""
		(layer "F.Cu")
		(at 34.1122 -116.2812)
		(property "Reference" "C322"
			(at 0 0 0)
			(layer "F.SilkS")
			(hide yes)
			(effects
				(font
					(size 1.27 1.27)
				)
			)
		)
		(property "Value" "SC1U25V3KX-1-GP"
			(at 0 -2.8194 0)
			(unlocked yes)
			(layer "F.Fab")
			(hide yes)
			(effects
				(font
					(size 1.016 1.016)
					(thickness 0.1524)
				)
			)
		)
		(property "Device Type" "C603H36"
			(at 0 -4.3434 0)
			(unlocked yes)
			(layer "F.Fab")
			(hide yes)
			(effects
				(font
					(size 1.016 1.016)
					(thickness 0.1524)
				)
			)
		)
		(duplicate_pad_numbers_are_jumpers no)
		(fp_line
			(start 0.508 0)
			(end -0.508 0)
			(stroke
				(width 0.2032)
				(type default)
			)
			(layer "F.SilkS")
		)
		(fp_rect
			(start -0.5842 1.3335)
			(end 0.5842 -1.3335)
			(stroke
				(width 0)
				(type default)
			)
			(fill no)
			(layer "F.CrtYd")
		)
		(fp_rect
			(start -0.5842 1.3335)
			(end 0.5842 -1.3335)
			(stroke
				(width 0)
				(type default)
			)
			(fill no)
			(layer "F.Fab")
		)
		(pad "1" smd custom
			(at 0 -0.762)
			(size 0.2159 0.2159)
			(layers "F.Cu" "F.Mask" "F.Paste")
			(net "P12V_HDD13")
			(options
				(clearance outline)
				(anchor circle)
			)
			(primitives
				(gr_poly
					(pts
						(arc
							(start -0.3302 -0.4318)
							(mid -0.402042 -0.402042)
							(end -0.4318 -0.3302)
						)
						(arc
							(start -0.4318 0.3302)
							(mid -0.402042 0.402042)
							(end -0.3302 0.4318)
						)
						(arc
							(start 0.3302 0.4318)
							(mid 0.402042 0.402042)
							(end 0.4318 0.3302)
						)
						(arc
							(start 0.4318 -0.3302)
							(mid 0.402042 -0.402042)
							(end 0.3302 -0.4318)
						)
					)
					(width 0)
					(fill yes)
				)
			)
		)
		(pad "2" smd custom
			(at 0 0.762)
			(size 0.2159 0.2159)
			(layers "F.Cu" "F.Mask" "F.Paste")
			(net "GND")
			(options
				(clearance outline)
				(anchor circle)
			)
			(primitives
				(gr_poly
					(pts
						(arc
							(start -0.3302 -0.4318)
							(mid -0.402042 -0.402042)
							(end -0.4318 -0.3302)
						)
						(arc
							(start -0.4318 0.3302)
							(mid -0.402042 0.402042)
							(end -0.3302 0.4318)
						)
						(arc
							(start 0.3302 0.4318)
							(mid 0.402042 0.402042)
							(end 0.4318 0.3302)
						)
						(arc
							(start 0.4318 -0.3302)
							(mid 0.402042 -0.402042)
							(end 0.3302 -0.4318)
						)
					)
					(width 0)
					(fill yes)
				)
			)
		)
	)
	(footprint ""
		(layer "F.Cu")
		(at 33.781746 -332.387702 180)
		(property "Reference" "C277"
			(at 0 0 180)
			(layer "F.SilkS")
			(hide yes)
			(effects
				(font
					(size 1.27 1.27)
				)
			)
		)
		(property "Value" "SCD1U10V2KX-5GP"
			(at 1.1811 -2.7051 180)
			(unlocked yes)
			(layer "F.Fab")
			(hide yes)
			(effects
				(font
					(size 1.016 1.016)
					(thickness 0.1524)
				)
			)
		)
		(property "Device Type" "C402H22"
			(at 1.1811 -4.2291 180)
			(unlocked yes)
			(layer "F.Fab")
			(hide yes)
			(effects
				(font
					(size 1.016 1.016)
					(thickness 0.1524)
				)
			)
		)
		(duplicate_pad_numbers_are_jumpers no)
		(fp_rect
			(start -0.4318 0.9525)
			(end 0.4318 -0.9525)
			(stroke
				(width 0)
				(type default)
			)
			(fill no)
			(layer "F.CrtYd")
		)
		(fp_rect
			(start -0.4318 0.9525)
			(end 0.4318 -0.9525)
			(stroke
				(width 0)
				(type default)
			)
			(fill no)
			(layer "F.Fab")
		)
		(pad "1" smd custom
			(at 0 -0.4445 180)
			(size 0.1524 0.1524)
			(layers "F.Cu" "F.Mask" "F.Paste")
			(net "P3V3")
			(options
				(clearance outline)
				(anchor circle)
			)
			(primitives
				(gr_poly
					(pts
						(arc
							(start 0.3048 -0.2032)
							(mid 0.275042 -0.275042)
							(end 0.2032 -0.3048)
						)
						(arc
							(start -0.2032 -0.3048)
							(mid -0.275042 -0.275042)
							(end -0.3048 -0.2032)
						)
						(arc
							(start -0.3048 0.2032)
							(mid -0.275042 0.275042)
							(end -0.2032 0.3048)
						)
						(arc
							(start 0.2032 0.3048)
							(mid 0.275042 0.275042)
							(end 0.3048 0.2032)
						)
					)
					(width 0)
					(fill yes)
				)
			)
		)
		(pad "2" smd custom
			(at 0 0.4445 180)
			(size 0.1524 0.1524)
			(layers "F.Cu" "F.Mask" "F.Paste")
			(net "GND")
			(options
				(clearance outline)
				(anchor circle)
			)
			(primitives
				(gr_poly
					(pts
						(arc
							(start 0.3048 -0.2032)
							(mid 0.275042 -0.275042)
							(end 0.2032 -0.3048)
						)
						(arc
							(start -0.2032 -0.3048)
							(mid -0.275042 -0.275042)
							(end -0.3048 -0.2032)
						)
						(arc
							(start -0.3048 0.2032)
							(mid -0.275042 0.275042)
							(end -0.2032 0.3048)
						)
						(arc
							(start 0.2032 0.3048)
							(mid 0.275042 0.275042)
							(end 0.3048 0.2032)
						)
					)
					(width 0)
					(fill yes)
				)
			)
		)
	)
	(footprint ""
		(layer "F.Cu")
		(at 47.243746 -214.404702)
		(property "Reference" "R275"
			(at 0 0 0)
			(layer "F.SilkS")
			(hide yes)
			(effects
				(font
					(size 1.27 1.27)
				)
			)
		)
		(property "Value" "200KR2F-L-GP"
			(at 0.064008 -3.993896 0)
			(unlocked yes)
			(layer "F.Fab")
			(hide yes)
			(effects
				(font
					(size 1.016 1.016)
					(thickness 0.1524)
				)
			)
		)
		(property "Device Type" "R402H16"
			(at 0.064008 -5.517896 0)
			(unlocked yes)
			(layer "F.Fab")
			(hide yes)
			(effects
				(font
					(size 1.016 1.016)
					(thickness 0.1524)
				)
			)
		)
		(duplicate_pad_numbers_are_jumpers no)
		(fp_line
			(start -0.508 -0.9398)
			(end -0.508 0.9398)
			(stroke
				(width 0.1524)
				(type default)
			)
			(layer "F.SilkS")
		)
		(fp_line
			(start 0.508 -0.9398)
			(end -0.508 -0.9398)
			(stroke
				(width 0.1524)
				(type default)
			)
			(layer "F.SilkS")
		)
		(fp_rect
			(start -0.508 0.9398)
			(end 0.508 -0.9398)
			(stroke
				(width 0)
				(type default)
			)
			(fill no)
			(layer "F.CrtYd")
		)
		(fp_rect
			(start -0.508 0.9398)
			(end 0.508 -0.9398)
			(stroke
				(width 0)
				(type default)
			)
			(fill no)
			(layer "F.Fab")
		)
		(pad "1" smd custom
			(at 0 -0.4445)
			(size 0.1397 0.1397)
			(layers "F.Cu" "F.Mask" "F.Paste")
			(net "P12V")
			(options
				(clearance outline)
				(anchor circle)
			)
			(primitives
				(gr_poly
					(pts
						(arc
							(start -0.1778 -0.2794)
							(mid -0.249642 -0.249642)
							(end -0.2794 -0.1778)
						)
						(arc
							(start -0.2794 0.1778)
							(mid -0.249642 0.249642)
							(end -0.1778 0.2794)
						)
						(arc
							(start 0.1778 0.2794)
							(mid 0.249642 0.249642)
							(end 0.2794 0.1778)
						)
						(arc
							(start 0.2794 -0.1778)
							(mid 0.249642 -0.249642)
							(end 0.1778 -0.2794)
						)
					)
					(width 0)
					(fill yes)
				)
			)
		)
		(pad "2" smd custom
			(at 0 0.4445)
			(size 0.1397 0.1397)
			(layers "F.Cu" "F.Mask" "F.Paste")
			(net "SW_HDD12_P")
			(options
				(clearance outline)
				(anchor circle)
			)
			(primitives
				(gr_poly
					(pts
						(arc
							(start -0.1778 -0.2794)
							(mid -0.249642 -0.249642)
							(end -0.2794 -0.1778)
						)
						(arc
							(start -0.2794 0.1778)
							(mid -0.249642 0.249642)
							(end -0.1778 0.2794)
						)
						(arc
							(start 0.1778 0.2794)
							(mid 0.249642 0.249642)
							(end 0.2794 0.1778)
						)
						(arc
							(start 0.2794 -0.1778)
							(mid 0.249642 -0.249642)
							(end 0.1778 -0.2794)
						)
					)
					(width 0)
					(fill yes)
				)
			)
		)
	)
	(footprint ""
		(layer "F.Cu")
		(at 56.133746 -381.1397)
		(property "Reference" "R191"
			(at 0 0 0)
			(layer "F.SilkS")
			(hide yes)
			(effects
				(font
					(size 1.27 1.27)
				)
			)
		)
		(property "Value" "220R3F-1-GP"
			(at -0.0254 -2.5146 0)
			(unlocked yes)
			(layer "F.Fab")
			(hide yes)
			(effects
				(font
					(size 1.016 1.016)
					(thickness 0.1524)
				)
			)
		)
		(property "Device Type" "R603H22"
			(at -0.0254 -4.0386 0)
			(unlocked yes)
			(layer "F.Fab")
			(hide yes)
			(effects
				(font
					(size 1.016 1.016)
					(thickness 0.1524)
				)
			)
		)
		(duplicate_pad_numbers_are_jumpers no)
		(fp_line
			(start -0.4826 0)
			(end -0.2032 0)
			(stroke
				(width 0.2032)
				(type default)
			)
			(layer "F.SilkS")
		)
		(fp_line
			(start 0.2032 0)
			(end 0.4826 0)
			(stroke
				(width 0.2032)
				(type default)
			)
			(layer "F.SilkS")
		)
		(fp_rect
			(start -0.5842 1.3335)
			(end 0.5842 -1.3335)
			(stroke
				(width 0)
				(type default)
			)
			(fill no)
			(layer "F.CrtYd")
		)
		(fp_rect
			(start -0.5842 1.3335)
			(end 0.5842 -1.3335)
			(stroke
				(width 0)
				(type default)
			)
			(fill no)
			(layer "F.Fab")
		)
		(pad "1" smd custom
			(at 0 -0.762)
			(size 0.2159 0.2159)
			(layers "F.Cu" "F.Mask" "F.Paste")
			(net "HDD_PRSNT_NET6")
			(options
				(clearance outline)
				(anchor circle)
			)
			(primitives
				(gr_poly
					(pts
						(arc
							(start -0.3302 -0.4318)
							(mid -0.402042 -0.402042)
							(end -0.4318 -0.3302)
						)
						(arc
							(start -0.4318 0.3302)
							(mid -0.402042 0.402042)
							(end -0.3302 0.4318)
						)
						(arc
							(start 0.3302 0.4318)
							(mid 0.402042 0.402042)
							(end 0.4318 0.3302)
						)
						(arc
							(start 0.4318 -0.3302)
							(mid 0.402042 -0.402042)
							(end 0.3302 -0.4318)
						)
					)
					(width 0)
					(fill yes)
				)
			)
		)
		(pad "2" smd custom
			(at 0 0.762)
			(size 0.2159 0.2159)
			(layers "F.Cu" "F.Mask" "F.Paste")
			(net "HDD_PRSNT6")
			(options
				(clearance outline)
				(anchor circle)
			)
			(primitives
				(gr_poly
					(pts
						(arc
							(start -0.3302 -0.4318)
							(mid -0.402042 -0.402042)
							(end -0.4318 -0.3302)
						)
						(arc
							(start -0.4318 0.3302)
							(mid -0.402042 0.402042)
							(end -0.3302 0.4318)
						)
						(arc
							(start 0.3302 0.4318)
							(mid 0.402042 0.402042)
							(end 0.4318 0.3302)
						)
						(arc
							(start 0.4318 -0.3302)
							(mid 0.402042 -0.402042)
							(end 0.3302 -0.4318)
						)
					)
					(width 0)
					(fill yes)
				)
			)
		)
	)
	(footprint ""
		(layer "F.Cu")
		(at 205.104746 -276.7457)
		(property "Reference" "TP27"
			(at 0 0 0)
			(layer "F.SilkS")
			(hide yes)
			(effects
				(font
					(size 1.27 1.27)
				)
			)
		)
		(property "Value" "TPAD32-GP"
			(at 0 -3.166364 0)
			(unlocked yes)
			(layer "F.Fab")
			(hide yes)
			(effects
				(font
					(size 1.016 1.016)
					(thickness 0.1524)
				)
			)
		)
		(property "Device Type" "TPAD32"
			(at 0 -4.690618 0)
			(unlocked yes)
			(layer "F.Fab")
			(hide yes)
			(effects
				(font
					(size 1.016 1.016)
					(thickness 0.1524)
				)
			)
		)
		(duplicate_pad_numbers_are_jumpers no)
		(fp_poly
			(pts
				(arc
					(start 0.4064 0)
					(mid -0.4064 0)
					(end 0.4064 0)
				)
			)
			(stroke
				(width 0)
				(type default)
			)
			(fill no)
			(layer "F.CrtYd")
		)
		(fp_poly
			(pts
				(arc
					(start 0.7112 0)
					(mid -0.7112 0)
					(end 0.7112 0)
				)
			)
			(stroke
				(width 0)
				(type default)
			)
			(fill no)
			(layer "F.Fab")
		)
		(pad "1" smd circle
			(at 0 0)
			(size 0.8128 0.8128)
			(layers "F.Cu" "F.Mask" "F.Paste")
			(net "ACT_HDD2")
		)
	)
	(footprint ""
		(layer "F.Cu")
		(at 29.590746 -336.070702)
		(property "Reference" "R464"
			(at 0 0 0)
			(layer "F.SilkS")
			(hide yes)
			(effects
				(font
					(size 1.27 1.27)
				)
			)
		)
		(property "Value" "4K7R2J-2-GP"
			(at 0.064008 -3.993896 0)
			(unlocked yes)
			(layer "F.Fab")
			(hide yes)
			(effects
				(font
					(size 1.016 1.016)
					(thickness 0.1524)
				)
			)
		)
		(property "Device Type" "R402H16"
			(at 0.064008 -5.517896 0)
			(unlocked yes)
			(layer "F.Fab")
			(hide yes)
			(effects
				(font
					(size 1.016 1.016)
					(thickness 0.1524)
				)
			)
		)
		(duplicate_pad_numbers_are_jumpers no)
		(fp_line
			(start -0.508 -0.9398)
			(end -0.508 0.9398)
			(stroke
				(width 0.1524)
				(type default)
			)
			(layer "F.SilkS")
		)
		(fp_line
			(start 0.508 -0.9398)
			(end -0.508 -0.9398)
			(stroke
				(width 0.1524)
				(type default)
			)
			(layer "F.SilkS")
		)
		(fp_rect
			(start -0.508 0.9398)
			(end 0.508 -0.9398)
			(stroke
				(width 0)
				(type default)
			)
			(fill no)
			(layer "F.CrtYd")
		)
		(fp_rect
			(start -0.508 0.9398)
			(end 0.508 -0.9398)
			(stroke
				(width 0)
				(type default)
			)
			(fill no)
			(layer "F.Fab")
		)
		(pad "1" smd custom
			(at 0 -0.4445)
			(size 0.1397 0.1397)
			(layers "F.Cu" "F.Mask" "F.Paste")
			(net "P3V3")
			(options
				(clearance outline)
				(anchor circle)
			)
			(primitives
				(gr_poly
					(pts
						(arc
							(start -0.1778 -0.2794)
							(mid -0.249642 -0.249642)
							(end -0.2794 -0.1778)
						)
						(arc
							(start -0.2794 0.1778)
							(mid -0.249642 0.249642)
							(end -0.1778 0.2794)
						)
						(arc
							(start 0.1778 0.2794)
							(mid 0.249642 0.249642)
							(end 0.2794 0.1778)
						)
						(arc
							(start 0.2794 -0.1778)
							(mid 0.249642 -0.249642)
							(end 0.1778 -0.2794)
						)
					)
					(width 0)
					(fill yes)
				)
			)
		)
		(pad "2" smd custom
			(at 0 0.4445)
			(size 0.1397 0.1397)
			(layers "F.Cu" "F.Mask" "F.Paste")
			(net "SAS2X28_A_HDD11_FLT")
			(options
				(clearance outline)
				(anchor circle)
			)
			(primitives
				(gr_poly
					(pts
						(arc
							(start -0.1778 -0.2794)
							(mid -0.249642 -0.249642)
							(end -0.2794 -0.1778)
						)
						(arc
							(start -0.2794 0.1778)
							(mid -0.249642 0.249642)
							(end -0.1778 0.2794)
						)
						(arc
							(start 0.1778 0.2794)
							(mid 0.249642 0.249642)
							(end 0.2794 0.1778)
						)
						(arc
							(start 0.2794 -0.1778)
							(mid 0.249642 -0.249642)
							(end 0.1778 -0.2794)
						)
					)
					(width 0)
					(fill yes)
				)
			)
		)
	)
)
